#ISCELL
  pure_quanta quanta_title_block_c *
  *
#ISCELL
  pure_quanta_power cad_note *
  *
#CELL
  pure_quanta genoa_sp5 *
  page21_i159
#ISCELL
  mstr_standard offpage *
  page21_i160
#ISCELL
  mstr_standard offpage *
  page21_i161
#ISCELL
  mstr_standard tap *
  page21_i162
#ISCELL
  mstr_standard tap *
  page21_i163
#ISCELL
  mstr_standard tap *
  page21_i164
#ISCELL
  mstr_standard tap *
  page21_i165
#ISCELL
  mstr_standard tap *
  page21_i166
#ISCELL
  mstr_standard tap *
  page21_i167
#ISCELL
  mstr_standard tap *
  page21_i168
#ISCELL
  mstr_standard tap *
  page21_i169
#ISCELL
  mstr_standard tap *
  page21_i170
#ISCELL
  mstr_standard tap *
  page21_i171
#ISCELL
  mstr_standard tap *
  page21_i172
#ISCELL
  mstr_standard tap *
  page21_i173
#ISCELL
  mstr_standard tap *
  page21_i174
#ISCELL
  mstr_standard tap *
  page21_i175
#ISCELL
  mstr_standard tap *
  page21_i176
#ISCELL
  mstr_standard tap *
  page21_i177
#ISCELL
  mstr_standard tap *
  page21_i178
#ISCELL
  mstr_standard tap *
  page21_i179
#ISCELL
  mstr_standard tap *
  page21_i180
#ISCELL
  mstr_standard tap *
  page21_i181
#ISCELL
  mstr_standard tap *
  page21_i182
#ISCELL
  mstr_standard tap *
  page21_i183
#ISCELL
  mstr_standard tap *
  page21_i184
#ISCELL
  mstr_standard tap *
  page21_i185
#ISCELL
  mstr_standard tap *
  page21_i186
#ISCELL
  mstr_standard tap *
  page21_i187
#ISCELL
  mstr_standard tap *
  page21_i188
#ISCELL
  mstr_standard tap *
  page21_i189
#ISCELL
  mstr_standard tap *
  page21_i190
#ISCELL
  mstr_standard tap *
  page21_i191
#ISCELL
  mstr_standard tap *
  page21_i192
#ISCELL
  mstr_standard tap *
  page21_i193
#ISCELL
  mstr_standard tap *
  page21_i194
#ISCELL
  mstr_standard tap *
  page21_i195
#ISCELL
  mstr_standard tap *
  page21_i196
#ISCELL
  mstr_standard offpage *
  page21_i197
#ISCELL
  mstr_standard tap *
  page21_i198
#ISCELL
  mstr_standard tap *
  page21_i199
#ISCELL
  mstr_standard tap *
  page21_i200
#ISCELL
  mstr_standard tap *
  page21_i201
#ISCELL
  mstr_standard tap *
  page21_i202
#ISCELL
  mstr_standard tap *
  page21_i203
#ISCELL
  mstr_standard tap *
  page21_i204
#ISCELL
  mstr_standard tap *
  page21_i205
#ISCELL
  mstr_standard tap *
  page21_i206
#ISCELL
  mstr_standard tap *
  page21_i207
#ISCELL
  mstr_standard tap *
  page21_i208
#ISCELL
  mstr_standard tap *
  page21_i209
#ISCELL
  mstr_standard tap *
  page21_i210
#ISCELL
  mstr_standard tap *
  page21_i211
#ISCELL
  mstr_standard tap *
  page21_i212
#ISCELL
  mstr_standard tap *
  page21_i213
#ISCELL
  mstr_standard tap *
  page21_i214
#ISCELL
  mstr_standard tap *
  page21_i215
#ISCELL
  mstr_standard tap *
  page21_i216
#ISCELL
  mstr_standard tap *
  page21_i217
#ISCELL
  mstr_standard tap *
  page21_i218
#ISCELL
  mstr_standard tap *
  page21_i219
#ISCELL
  mstr_standard tap *
  page21_i220
#ISCELL
  mstr_standard tap *
  page21_i221
#ISCELL
  mstr_standard tap *
  page21_i222
#ISCELL
  mstr_standard tap *
  page21_i223
#ISCELL
  mstr_standard tap *
  page21_i224
#ISCELL
  mstr_standard tap *
  page21_i225
#ISCELL
  mstr_standard tap *
  page21_i226
#ISCELL
  mstr_standard tap *
  page21_i227
#ISCELL
  mstr_standard tap *
  page21_i228
#ISCELL
  mstr_standard tap *
  page21_i229
#ISCELL
  mstr_standard tap *
  page21_i230
#ISCELL
  mstr_standard tap *
  page21_i231
#ISCELL
  mstr_standard tap *
  page21_i232
#ISCELL
  mstr_standard tap *
  page21_i233
#ISCELL
  mstr_standard tap *
  page21_i234
#ISCELL
  mstr_standard offpage *
  page21_i235
#ISCELL
  mstr_standard tap *
  page21_i236
#ISCELL
  mstr_standard tap *
  page21_i237
#ISCELL
  mstr_standard tap *
  page21_i238
#ISCELL
  mstr_standard tap *
  page21_i239
#ISCELL
  mstr_standard tap *
  page21_i240
#ISCELL
  mstr_standard tap *
  page21_i241
#ISCELL
  mstr_standard tap *
  page21_i242
#ISCELL
  mstr_standard tap *
  page21_i243
#ISCELL
  mstr_standard tap *
  page21_i244
#ISCELL
  mstr_standard tap *
  page21_i245
#ISCELL
  mstr_standard tap *
  page21_i246
#ISCELL
  mstr_standard tap *
  page21_i247
#ISCELL
  mstr_standard tap *
  page21_i248
#ISCELL
  mstr_standard tap *
  page21_i249
#ISCELL
  mstr_standard tap *
  page21_i250
#ISCELL
  mstr_standard tap *
  page21_i251
#ISCELL
  mstr_standard tap *
  page21_i252
#ISCELL
  mstr_standard tap *
  page21_i253
#ISCELL
  mstr_standard tap *
  page21_i254
#ISCELL
  mstr_standard tap *
  page21_i255
#ISCELL
  mstr_standard tap *
  page21_i256
#ISCELL
  mstr_standard tap *
  page21_i257
#ISCELL
  mstr_standard tap *
  page21_i258
#ISCELL
  mstr_standard tap *
  page21_i259
#ISCELL
  mstr_standard tap *
  page21_i260
#ISCELL
  mstr_standard tap *
  page21_i261
#ISCELL
  mstr_standard tap *
  page21_i262
#ISCELL
  mstr_standard tap *
  page21_i263
#ISCELL
  mstr_standard tap *
  page21_i264
#ISCELL
  mstr_standard tap *
  page21_i265
#ISCELL
  mstr_standard tap *
  page21_i266
#ISCELL
  mstr_standard tap *
  page21_i267
#ISCELL
  mstr_standard tap *
  page21_i268
#ISCELL
  mstr_standard tap *
  page21_i269
#ISCELL
  mstr_standard tap *
  page21_i270
#ISCELL
  mstr_standard tap *
  page21_i271
#ISCELL
  mstr_standard tap *
  page21_i272
#ISCELL
  mstr_standard tap *
  page21_i273
#ISCELL
  mstr_standard tap *
  page21_i274
#ISCELL
  mstr_standard tap *
  page21_i275
#ISCELL
  mstr_standard tap *
  page21_i276
#ISCELL
  mstr_standard tap *
  page21_i277
#ISCELL
  mstr_standard tap *
  page21_i278
#ISCELL
  mstr_standard tap *
  page21_i279
#ISCELL
  mstr_standard tap *
  page21_i280
#ISCELL
  mstr_standard tap *
  page21_i281
#ISCELL
  standard offpage *
  page21_i282
#ISCELL
  standard offpage *
  page21_i283
#ISCELL
  standard offpage *
  page21_i284
#ISCELL
  standard offpage *
  page21_i285
#ISCELL
  mstr_standard tap *
  page21_i286
#ISCELL
  mstr_standard tap *
  page21_i287
#ISCELL
  mstr_standard tap *
  page21_i288
#ISCELL
  mstr_standard tap *
  page21_i289
#ISCELL
  mstr_standard tap *
  page21_i290
#ISCELL
  mstr_standard tap *
  page21_i291
#ISCELL
  mstr_standard tap *
  page21_i292
#ISCELL
  mstr_standard tap *
  page21_i293
#ISCELL
  mstr_standard tap *
  page21_i294
#ISCELL
  mstr_standard tap *
  page21_i295
#ISCELL
  mstr_standard tap *
  page21_i296
#ISCELL
  mstr_standard tap *
  page21_i297
#ISCELL
  mstr_standard tap *
  page21_i298
#ISCELL
  mstr_standard tap *
  page21_i299
#ISCELL
  mstr_standard tap *
  page21_i300
#ISCELL
  mstr_standard tap *
  page21_i301
#ISCELL
  standard offpage *
  page21_i302
#ISCELL
  standard offpage *
  page21_i303
#ISCELL
  standard offpage *
  page21_i304
#ISCELL
  standard offpage *
  page21_i305
#ISCELL
  standard offpage *
  page21_i306
#ISCELL
  mstr_standard offpage *
  page21_i307
#ISCELL
  standard offpage *
  page21_i308
#ISCELL
  standard offpage *
  page21_i309
#ISCELL
  standard offpage *
  page21_i310
#ISCELL
  standard offpage *
  page21_i311
#ISCELL
  standard offpage *
  page21_i312
#ISCELL
  standard offpage *
  page21_i313
#CELL
  pure_quanta q_res *
  page21_i314
#ISCELL
  mstr_standard offpage *
  page21_i315
#ISCELL
  standard offpage *
  page21_i316
